(kicad_pcb
	(version 20260206)
	(generator "pcbnew")
	(generator_version "10.0")
	(general
		(thickness 1.6)
		(legacy_teardrops no)
	)
	(paper "A4")
	(title_block
		(title "01162023_DA0F0TEBIF0_F0T_Expander_BD_F_brd_V02_OCP.brd")
		(comment 1 "Grand Teton / footprints 8441-8448 of 9728")
	)
	(layers
		(0 "F.Cu" signal "TOP")
		(4 "In1.Cu" signal "GND")
		(6 "In2.Cu" signal "VCC")
		(8 "In3.Cu" signal "VCC1")
		(10 "In4.Cu" signal "GND1")
		(12 "In5.Cu" signal "IN1")
		(14 "In6.Cu" signal "GND2")
		(16 "In7.Cu" signal "IN2")
		(18 "In8.Cu" signal "GND3")
		(20 "In9.Cu" signal "IN3")
		(22 "In10.Cu" signal "GND4")
		(24 "In11.Cu" signal "IN4")
		(26 "In12.Cu" signal "GND5")
		(28 "In13.Cu" signal "IN5")
		(30 "In14.Cu" signal "GND6")
		(32 "In15.Cu" signal "IN6")
		(34 "In16.Cu" signal "GND7")
		(2 "B.Cu" signal "BOTTOM")
		(9 "F.Adhes" user "F.Adhesive")
		(11 "B.Adhes" user "B.Adhesive")
		(13 "F.Paste" user "Package Geometry/Pastemask Top")
		(15 "B.Paste" user "Package Geometry/Pastemask Bottom")
		(5 "F.SilkS" user "Ref Des/Silkscreen Top")
		(7 "B.SilkS" user "Ref Des/Silkscreen Bottom")
		(1 "F.Mask" user "Board Geometry/Soldermask Top")
		(3 "B.Mask" user "Board Geometry/Soldermask Bottom")
		(17 "Dwgs.User" user "User.Drawings")
		(19 "Cmts.User" user "User.Comments")
		(21 "Eco1.User" user "User.Eco1")
		(23 "Eco2.User" user "User.Eco2")
		(25 "Edge.Cuts" user "Board Geometry/Outline")
		(27 "Margin" user)
		(31 "F.CrtYd" user "Package Geometry/Place Bound Top")
		(29 "B.CrtYd" user "Package Geometry/Place Bound Bottom")
		(35 "F.Fab" user "Ref Des/Assembly Top")
		(33 "B.Fab" user "Ref Des/Assembly Bottom")
	)
	(footprint ""
		(layer "B.Cu")
		(at 308.02072 -114.35207 90)
		(property "Reference" "C927"
			(at 0 0 90)
			(layer "B.SilkS")
			(hide yes)
			(effects
				(font
					(size 1.27 1.27)
				)
				(justify mirror)
			)
		)
		(property "Value" ""
			(at 0 0 90)
			(layer "B.Fab")
			(effects
				(font
					(size 1.27 1.27)
				)
				(justify mirror)
			)
		)
		(duplicate_pad_numbers_are_jumpers no)
		(fp_line
			(start 0.7874 -0.4064)
			(end -0.7874 -0.4064)
			(stroke
				(width 0.1524)
				(type default)
			)
			(layer "B.SilkS")
		)
		(fp_line
			(start -0.7874 -0.4064)
			(end -0.7874 0.4064)
			(stroke
				(width 0.1524)
				(type default)
			)
			(layer "B.SilkS")
		)
		(fp_line
			(start 0.7874 0.4064)
			(end 0.7874 -0.4064)
			(stroke
				(width 0.1524)
				(type default)
			)
			(layer "B.SilkS")
		)
		(fp_line
			(start -0.7874 0.4064)
			(end 0.7874 0.4064)
			(stroke
				(width 0.1524)
				(type default)
			)
			(layer "B.SilkS")
		)
		(fp_line
			(start 0.67945 -0.305054)
			(end 0.12065 -0.305054)
			(stroke
				(width 0.1)
				(type default)
			)
			(layer "B.Fab")
		)
		(fp_line
			(start 0.12065 -0.305054)
			(end 0.12065 -0.2794)
			(stroke
				(width 0.1)
				(type default)
			)
			(layer "B.Fab")
		)
		(fp_line
			(start -0.12065 -0.3048)
			(end -0.67945 -0.3048)
			(stroke
				(width 0.1)
				(type default)
			)
			(layer "B.Fab")
		)
		(fp_line
			(start -0.67945 -0.3048)
			(end -0.67945 0.3048)
			(stroke
				(width 0.1)
				(type default)
			)
			(layer "B.Fab")
		)
		(fp_line
			(start 0.12065 -0.2794)
			(end -0.12065 -0.2794)
			(stroke
				(width 0.1)
				(type default)
			)
			(layer "B.Fab")
		)
		(fp_line
			(start -0.12065 -0.2794)
			(end -0.12065 -0.3048)
			(stroke
				(width 0.1)
				(type default)
			)
			(layer "B.Fab")
		)
		(fp_line
			(start 0.12065 0.2794)
			(end 0.12065 0.3048)
			(stroke
				(width 0.1)
				(type default)
			)
			(layer "B.Fab")
		)
		(fp_line
			(start -0.120396 0.2794)
			(end 0.12065 0.2794)
			(stroke
				(width 0.1)
				(type default)
			)
			(layer "B.Fab")
		)
		(fp_line
			(start 0.67945 0.3048)
			(end 0.67945 -0.305054)
			(stroke
				(width 0.1)
				(type default)
			)
			(layer "B.Fab")
		)
		(fp_line
			(start 0.12065 0.3048)
			(end 0.67945 0.3048)
			(stroke
				(width 0.1)
				(type default)
			)
			(layer "B.Fab")
		)
		(fp_line
			(start -0.120396 0.3048)
			(end -0.120396 0.2794)
			(stroke
				(width 0.1)
				(type default)
			)
			(layer "B.Fab")
		)
		(fp_line
			(start -0.67945 0.3048)
			(end -0.120396 0.3048)
			(stroke
				(width 0.1)
				(type default)
			)
			(layer "B.Fab")
		)
		(pad "1" smd circle
			(at 0.40005 0 270)
			(size 0 0)
			(layers "B.Cu" "B.Mask" "B.Paste")
			(net "P3V3_NIC5")
		)
		(pad "2" smd circle
			(at -0.40005 0 270)
			(size 0 0)
			(layers "B.Cu" "B.Mask" "B.Paste")
			(net "GND")
		)
	)
	(footprint ""
		(layer "B.Cu")
		(at 58.224928 -293.99992 90)
		(property "Reference" "C1155"
			(at 0 0 90)
			(layer "B.SilkS")
			(hide yes)
			(effects
				(font
					(size 1.27 1.27)
				)
				(justify mirror)
			)
		)
		(property "Value" ""
			(at 0 0 90)
			(layer "B.Fab")
			(effects
				(font
					(size 1.27 1.27)
				)
				(justify mirror)
			)
		)
		(duplicate_pad_numbers_are_jumpers no)
		(fp_line
			(start 0.299974 -0.150114)
			(end -0.299974 -0.150114)
			(stroke
				(width 0.1)
				(type default)
			)
			(layer "B.Fab")
		)
		(fp_line
			(start -0.299974 -0.150114)
			(end -0.299974 0.150114)
			(stroke
				(width 0.1)
				(type default)
			)
			(layer "B.Fab")
		)
		(fp_line
			(start 0.299974 0.150114)
			(end 0.299974 -0.150114)
			(stroke
				(width 0.1)
				(type default)
			)
			(layer "B.Fab")
		)
		(fp_line
			(start -0.299974 0.150114)
			(end 0.299974 0.150114)
			(stroke
				(width 0.1)
				(type default)
			)
			(layer "B.Fab")
		)
		(pad "1" smd rect
			(at 0.2667 0 270)
			(size 0.3048 0.381)
			(layers "B.Cu" "B.Mask" "B.Paste")
			(net "P0V8_PEX0")
		)
		(pad "2" smd rect
			(at -0.2667 0 270)
			(size 0.3048 0.381)
			(layers "B.Cu" "B.Mask" "B.Paste")
			(net "GND")
		)
	)
	(footprint ""
		(layer "B.Cu")
		(at 236.540294 -224.060258 90)
		(property "Reference" "R6821"
			(at 0 0 90)
			(layer "B.SilkS")
			(hide yes)
			(effects
				(font
					(size 1.27 1.27)
				)
				(justify mirror)
			)
		)
		(property "Value" ""
			(at 0 0 90)
			(layer "B.Fab")
			(effects
				(font
					(size 1.27 1.27)
				)
				(justify mirror)
			)
		)
		(duplicate_pad_numbers_are_jumpers no)
		(fp_line
			(start 0.7874 -0.4064)
			(end -0.7874 -0.4064)
			(stroke
				(width 0.1524)
				(type default)
			)
			(layer "B.SilkS")
		)
		(fp_line
			(start -0.7874 -0.4064)
			(end -0.7874 0.4064)
			(stroke
				(width 0.1524)
				(type default)
			)
			(layer "B.SilkS")
		)
		(fp_line
			(start 0.7874 0.4064)
			(end 0.7874 -0.4064)
			(stroke
				(width 0.1524)
				(type default)
			)
			(layer "B.SilkS")
		)
		(fp_line
			(start -0.7874 0.4064)
			(end 0.7874 0.4064)
			(stroke
				(width 0.1524)
				(type default)
			)
			(layer "B.SilkS")
		)
		(fp_line
			(start 0.67945 -0.305054)
			(end 0.12065 -0.305054)
			(stroke
				(width 0.1)
				(type default)
			)
			(layer "B.Fab")
		)
		(fp_line
			(start 0.12065 -0.305054)
			(end 0.12065 -0.2794)
			(stroke
				(width 0.1)
				(type default)
			)
			(layer "B.Fab")
		)
		(fp_line
			(start -0.12065 -0.3048)
			(end -0.67945 -0.3048)
			(stroke
				(width 0.1)
				(type default)
			)
			(layer "B.Fab")
		)
		(fp_line
			(start -0.67945 -0.3048)
			(end -0.67945 0.3048)
			(stroke
				(width 0.1)
				(type default)
			)
			(layer "B.Fab")
		)
		(fp_line
			(start 0.12065 -0.2794)
			(end -0.12065 -0.2794)
			(stroke
				(width 0.1)
				(type default)
			)
			(layer "B.Fab")
		)
		(fp_line
			(start -0.12065 -0.2794)
			(end -0.12065 -0.3048)
			(stroke
				(width 0.1)
				(type default)
			)
			(layer "B.Fab")
		)
		(fp_line
			(start 0.12065 0.2794)
			(end 0.12065 0.3048)
			(stroke
				(width 0.1)
				(type default)
			)
			(layer "B.Fab")
		)
		(fp_line
			(start -0.120396 0.2794)
			(end 0.12065 0.2794)
			(stroke
				(width 0.1)
				(type default)
			)
			(layer "B.Fab")
		)
		(fp_line
			(start 0.67945 0.3048)
			(end 0.67945 -0.305054)
			(stroke
				(width 0.1)
				(type default)
			)
			(layer "B.Fab")
		)
		(fp_line
			(start 0.12065 0.3048)
			(end 0.67945 0.3048)
			(stroke
				(width 0.1)
				(type default)
			)
			(layer "B.Fab")
		)
		(fp_line
			(start -0.120396 0.3048)
			(end -0.120396 0.2794)
			(stroke
				(width 0.1)
				(type default)
			)
			(layer "B.Fab")
		)
		(fp_line
			(start -0.67945 0.3048)
			(end -0.120396 0.3048)
			(stroke
				(width 0.1)
				(type default)
			)
			(layer "B.Fab")
		)
		(pad "1" smd circle
			(at 0.40005 0 270)
			(size 0 0)
			(layers "B.Cu" "B.Mask" "B.Paste")
			(net "VR_TYPE_ADC_R")
		)
		(pad "2" smd circle
			(at -0.40005 0 270)
			(size 0 0)
			(layers "B.Cu" "B.Mask" "B.Paste")
			(net "P3V3_AUX")
		)
	)
	(footprint ""
		(layer "B.Cu")
		(at 288.52495 -293.99992 90)
		(property "Reference" "C1621"
			(at 0 0 90)
			(layer "B.SilkS")
			(hide yes)
			(effects
				(font
					(size 1.27 1.27)
				)
				(justify mirror)
			)
		)
		(property "Value" ""
			(at 0 0 90)
			(layer "B.Fab")
			(effects
				(font
					(size 1.27 1.27)
				)
				(justify mirror)
			)
		)
		(duplicate_pad_numbers_are_jumpers no)
		(fp_line
			(start 0.299974 -0.150114)
			(end -0.299974 -0.150114)
			(stroke
				(width 0.1)
				(type default)
			)
			(layer "B.Fab")
		)
		(fp_line
			(start -0.299974 -0.150114)
			(end -0.299974 0.150114)
			(stroke
				(width 0.1)
				(type default)
			)
			(layer "B.Fab")
		)
		(fp_line
			(start 0.299974 0.150114)
			(end 0.299974 -0.150114)
			(stroke
				(width 0.1)
				(type default)
			)
			(layer "B.Fab")
		)
		(fp_line
			(start -0.299974 0.150114)
			(end 0.299974 0.150114)
			(stroke
				(width 0.1)
				(type default)
			)
			(layer "B.Fab")
		)
		(pad "1" smd rect
			(at 0.2667 0 270)
			(size 0.3048 0.381)
			(layers "B.Cu" "B.Mask" "B.Paste")
			(net "P0V8_PEX2")
		)
		(pad "2" smd rect
			(at -0.2667 0 270)
			(size 0.3048 0.381)
			(layers "B.Cu" "B.Mask" "B.Paste")
			(net "GND")
		)
	)
	(footprint ""
		(layer "B.Cu")
		(at 261.904226 -225.76663 180)
		(property "Reference" "R6169"
			(at 0 0 0)
			(layer "B.SilkS")
			(hide yes)
			(effects
				(font
					(size 1.27 1.27)
				)
				(justify mirror)
			)
		)
		(property "Value" ""
			(at 0 0 0)
			(layer "B.Fab")
			(effects
				(font
					(size 1.27 1.27)
				)
				(justify mirror)
			)
		)
		(duplicate_pad_numbers_are_jumpers no)
		(fp_line
			(start 0.7874 0.4064)
			(end 0.7874 -0.4064)
			(stroke
				(width 0.1524)
				(type default)
			)
			(layer "B.SilkS")
		)
		(fp_line
			(start 0.7874 -0.4064)
			(end -0.7874 -0.4064)
			(stroke
				(width 0.1524)
				(type default)
			)
			(layer "B.SilkS")
		)
		(fp_line
			(start -0.7874 0.4064)
			(end 0.7874 0.4064)
			(stroke
				(width 0.1524)
				(type default)
			)
			(layer "B.SilkS")
		)
		(fp_line
			(start -0.7874 -0.4064)
			(end -0.7874 0.4064)
			(stroke
				(width 0.1524)
				(type default)
			)
			(layer "B.SilkS")
		)
		(fp_line
			(start 0.67945 0.3048)
			(end 0.67945 -0.305054)
			(stroke
				(width 0.1)
				(type default)
			)
			(layer "B.Fab")
		)
		(fp_line
			(start 0.67945 -0.305054)
			(end 0.12065 -0.305054)
			(stroke
				(width 0.1)
				(type default)
			)
			(layer "B.Fab")
		)
		(fp_line
			(start 0.12065 0.3048)
			(end 0.67945 0.3048)
			(stroke
				(width 0.1)
				(type default)
			)
			(layer "B.Fab")
		)
		(fp_line
			(start 0.12065 0.2794)
			(end 0.12065 0.3048)
			(stroke
				(width 0.1)
				(type default)
			)
			(layer "B.Fab")
		)
		(fp_line
			(start 0.12065 -0.2794)
			(end -0.12065 -0.2794)
			(stroke
				(width 0.1)
				(type default)
			)
			(layer "B.Fab")
		)
		(fp_line
			(start 0.12065 -0.305054)
			(end 0.12065 -0.2794)
			(stroke
				(width 0.1)
				(type default)
			)
			(layer "B.Fab")
		)
		(fp_line
			(start -0.120396 0.3048)
			(end -0.120396 0.2794)
			(stroke
				(width 0.1)
				(type default)
			)
			(layer "B.Fab")
		)
		(fp_line
			(start -0.120396 0.2794)
			(end 0.12065 0.2794)
			(stroke
				(width 0.1)
				(type default)
			)
			(layer "B.Fab")
		)
		(fp_line
			(start -0.12065 -0.2794)
			(end -0.12065 -0.3048)
			(stroke
				(width 0.1)
				(type default)
			)
			(layer "B.Fab")
		)
		(fp_line
			(start -0.12065 -0.3048)
			(end -0.67945 -0.3048)
			(stroke
				(width 0.1)
				(type default)
			)
			(layer "B.Fab")
		)
		(fp_line
			(start -0.67945 0.3048)
			(end -0.120396 0.3048)
			(stroke
				(width 0.1)
				(type default)
			)
			(layer "B.Fab")
		)
		(fp_line
			(start -0.67945 -0.3048)
			(end -0.67945 0.3048)
			(stroke
				(width 0.1)
				(type default)
			)
			(layer "B.Fab")
		)
		(pad "1" smd circle
			(at 0.40005 0)
			(size 0 0)
			(layers "B.Cu" "B.Mask" "B.Paste")
			(net "SPI_PEX2_RST_R_N")
		)
		(pad "2" smd circle
			(at -0.40005 0)
			(size 0 0)
			(layers "B.Cu" "B.Mask" "B.Paste")
			(net "P1V8_PEX")
		)
	)
	(footprint ""
		(layer "B.Cu")
		(at 425.841922 -99.037648 180)
		(property "Reference" "R371"
			(at 0 0 0)
			(layer "B.SilkS")
			(hide yes)
			(effects
				(font
					(size 1.27 1.27)
				)
				(justify mirror)
			)
		)
		(property "Value" ""
			(at 0 0 0)
			(layer "B.Fab")
			(effects
				(font
					(size 1.27 1.27)
				)
				(justify mirror)
			)
		)
		(duplicate_pad_numbers_are_jumpers no)
		(fp_line
			(start 0.7874 0.4064)
			(end 0.7874 -0.4064)
			(stroke
				(width 0.1524)
				(type default)
			)
			(layer "B.SilkS")
		)
		(fp_line
			(start 0.7874 -0.4064)
			(end -0.7874 -0.4064)
			(stroke
				(width 0.1524)
				(type default)
			)
			(layer "B.SilkS")
		)
		(fp_line
			(start -0.7874 0.4064)
			(end 0.7874 0.4064)
			(stroke
				(width 0.1524)
				(type default)
			)
			(layer "B.SilkS")
		)
		(fp_line
			(start -0.7874 -0.4064)
			(end -0.7874 0.4064)
			(stroke
				(width 0.1524)
				(type default)
			)
			(layer "B.SilkS")
		)
		(fp_line
			(start 0.67945 0.3048)
			(end 0.67945 -0.305054)
			(stroke
				(width 0.1)
				(type default)
			)
			(layer "B.Fab")
		)
		(fp_line
			(start 0.67945 -0.305054)
			(end 0.12065 -0.305054)
			(stroke
				(width 0.1)
				(type default)
			)
			(layer "B.Fab")
		)
		(fp_line
			(start 0.12065 0.3048)
			(end 0.67945 0.3048)
			(stroke
				(width 0.1)
				(type default)
			)
			(layer "B.Fab")
		)
		(fp_line
			(start 0.12065 0.2794)
			(end 0.12065 0.3048)
			(stroke
				(width 0.1)
				(type default)
			)
			(layer "B.Fab")
		)
		(fp_line
			(start 0.12065 -0.2794)
			(end -0.12065 -0.2794)
			(stroke
				(width 0.1)
				(type default)
			)
			(layer "B.Fab")
		)
		(fp_line
			(start 0.12065 -0.305054)
			(end 0.12065 -0.2794)
			(stroke
				(width 0.1)
				(type default)
			)
			(layer "B.Fab")
		)
		(fp_line
			(start -0.120396 0.3048)
			(end -0.120396 0.2794)
			(stroke
				(width 0.1)
				(type default)
			)
			(layer "B.Fab")
		)
		(fp_line
			(start -0.120396 0.2794)
			(end 0.12065 0.2794)
			(stroke
				(width 0.1)
				(type default)
			)
			(layer "B.Fab")
		)
		(fp_line
			(start -0.12065 -0.2794)
			(end -0.12065 -0.3048)
			(stroke
				(width 0.1)
				(type default)
			)
			(layer "B.Fab")
		)
		(fp_line
			(start -0.12065 -0.3048)
			(end -0.67945 -0.3048)
			(stroke
				(width 0.1)
				(type default)
			)
			(layer "B.Fab")
		)
		(fp_line
			(start -0.67945 0.3048)
			(end -0.120396 0.3048)
			(stroke
				(width 0.1)
				(type default)
			)
			(layer "B.Fab")
		)
		(fp_line
			(start -0.67945 -0.3048)
			(end -0.67945 0.3048)
			(stroke
				(width 0.1)
				(type default)
			)
			(layer "B.Fab")
		)
		(pad "1" smd circle
			(at 0.40005 0)
			(size 0 0)
			(layers "B.Cu" "B.Mask" "B.Paste")
			(net "NIC7_CLK")
		)
		(pad "2" smd circle
			(at -0.40005 0)
			(size 0 0)
			(layers "B.Cu" "B.Mask" "B.Paste")
			(net "GND")
		)
	)
	(footprint ""
		(layer "B.Cu")
		(at 293.74973 -290.199826 90)
		(property "Reference" "C1731"
			(at 0 0 90)
			(layer "B.SilkS")
			(hide yes)
			(effects
				(font
					(size 1.27 1.27)
				)
				(justify mirror)
			)
		)
		(property "Value" ""
			(at 0 0 90)
			(layer "B.Fab")
			(effects
				(font
					(size 1.27 1.27)
				)
				(justify mirror)
			)
		)
		(duplicate_pad_numbers_are_jumpers no)
		(fp_line
			(start 0.299974 -0.150114)
			(end -0.299974 -0.150114)
			(stroke
				(width 0.1)
				(type default)
			)
			(layer "B.Fab")
		)
		(fp_line
			(start -0.299974 -0.150114)
			(end -0.299974 0.150114)
			(stroke
				(width 0.1)
				(type default)
			)
			(layer "B.Fab")
		)
		(fp_line
			(start 0.299974 0.150114)
			(end 0.299974 -0.150114)
			(stroke
				(width 0.1)
				(type default)
			)
			(layer "B.Fab")
		)
		(fp_line
			(start -0.299974 0.150114)
			(end 0.299974 0.150114)
			(stroke
				(width 0.1)
				(type default)
			)
			(layer "B.Fab")
		)
		(pad "1" smd rect
			(at 0.2667 0 270)
			(size 0.3048 0.381)
			(layers "B.Cu" "B.Mask" "B.Paste")
			(net "P0V8_SERDES_VDDA_PEX2")
		)
		(pad "2" smd rect
			(at -0.2667 0 270)
			(size 0.3048 0.381)
			(layers "B.Cu" "B.Mask" "B.Paste")
			(net "GND")
		)
	)
	(footprint ""
		(layer "B.Cu")
		(at 399.82013 -305.399948 -90)
		(property "Reference" "C3490"
			(at 0 0 90)
			(layer "B.SilkS")
			(hide yes)
			(effects
				(font
					(size 1.27 1.27)
				)
				(justify mirror)
			)
		)
		(property "Value" ""
			(at 0 0 90)
			(layer "B.Fab")
			(effects
				(font
					(size 1.27 1.27)
				)
				(justify mirror)
			)
		)
		(duplicate_pad_numbers_are_jumpers no)
		(fp_line
			(start -0.299974 0.150114)
			(end 0.299974 0.150114)
			(stroke
				(width 0.1)
				(type default)
			)
			(layer "B.Fab")
		)
		(fp_line
			(start 0.299974 0.150114)
			(end 0.299974 -0.150114)
			(stroke
				(width 0.1)
				(type default)
			)
			(layer "B.Fab")
		)
		(fp_line
			(start -0.299974 -0.150114)
			(end -0.299974 0.150114)
			(stroke
				(width 0.1)
				(type default)
			)
			(layer "B.Fab")
		)
		(fp_line
			(start 0.299974 -0.150114)
			(end -0.299974 -0.150114)
			(stroke
				(width 0.1)
				(type default)
			)
			(layer "B.Fab")
		)
		(pad "1" smd rect
			(at 0.2667 0 90)
			(size 0.3048 0.381)
			(layers "B.Cu" "B.Mask" "B.Paste")
			(net "P1V25_SERDES_VDDPLL_PEX3")
		)
		(pad "2" smd rect
			(at -0.2667 0 90)
			(size 0.3048 0.381)
			(layers "B.Cu" "B.Mask" "B.Paste")
			(net "GND")
		)
	)
)
